(kicad_pcb
	(version 20260206)
	(generator "pcbnew")
	(generator_version "10.0")
	(general
		(thickness 1.6)
		(legacy_teardrops no)
	)
	(paper "A4")
	(title_block
		(title "Wiwynn_Tioga_Pass_MB.brd")
		(comment 1 "Tioga Pass / footprints 1665-1672 of 4770")
	)
	(layers
		(0 "F.Cu" signal "TOP")
		(4 "In1.Cu" signal "L2GND")
		(6 "In2.Cu" signal "L3")
		(8 "In3.Cu" signal "L4GND")
		(10 "In4.Cu" signal "L5")
		(12 "In5.Cu" signal "L6GND")
		(14 "In6.Cu" signal "L7VCC")
		(16 "In7.Cu" signal "L8VCC")
		(18 "In8.Cu" signal "L9GND")
		(20 "In9.Cu" signal "L10")
		(22 "In10.Cu" signal "L11GND")
		(24 "In11.Cu" signal "L12")
		(26 "In12.Cu" signal "L13GND")
		(2 "B.Cu" signal "BOTTOM")
		(9 "F.Adhes" user "F.Adhesive")
		(11 "B.Adhes" user "B.Adhesive")
		(13 "F.Paste" user "Package Geometry/Pastemask Top")
		(15 "B.Paste" user "Package Geometry/Pastemask Bottom")
		(5 "F.SilkS" user "Ref Des/Silkscreen Top")
		(7 "B.SilkS" user "Ref Des/Silkscreen Bottom")
		(1 "F.Mask" user "Board Geometry/Soldermask Top")
		(3 "B.Mask" user "Board Geometry/Soldermask Bottom")
		(17 "Dwgs.User" user "User.Drawings")
		(19 "Cmts.User" user "User.Comments")
		(21 "Eco1.User" user "User.Eco1")
		(23 "Eco2.User" user "User.Eco2")
		(25 "Edge.Cuts" user "Board Geometry/Outline")
		(27 "Margin" user)
		(31 "F.CrtYd" user "Package Geometry/Place Bound Top")
		(29 "B.CrtYd" user "Package Geometry/Place Bound Bottom")
		(35 "F.Fab" user "Ref Des/Assembly Top")
		(33 "B.Fab" user "Ref Des/Assembly Bottom")
	)
	(footprint ""
		(layer "F.Cu")
		(at 392.785346 -64.959738 90)
		(property "Reference" "R8E39"
			(at 0 0 90)
			(layer "F.SilkS")
			(hide yes)
			(effects
				(font
					(size 1.27 1.27)
				)
			)
		)
		(property "Value" ""
			(at 0 0 90)
			(layer "F.Fab")
			(effects
				(font
					(size 1.27 1.27)
				)
			)
		)
		(duplicate_pad_numbers_are_jumpers no)
		(fp_poly
			(pts
				(xy -0.2794 -0.1016) (xy 0.2794 -0.1016) (xy 0.2794 0.9906) (xy -0.2794 0.9906)
			)
			(stroke
				(width 0)
				(type default)
			)
			(fill no)
			(layer "F.CrtYd")
		)
		(fp_line
			(start 0.2794 -0.1016)
			(end -0.2794 -0.1016)
			(stroke
				(width 0.1)
				(type default)
			)
			(layer "F.Fab")
		)
		(fp_line
			(start -0.2794 -0.1016)
			(end -0.2794 0.9906)
			(stroke
				(width 0.1)
				(type default)
			)
			(layer "F.Fab")
		)
		(fp_line
			(start 0.2794 0.9906)
			(end 0.2794 -0.1016)
			(stroke
				(width 0.1)
				(type default)
			)
			(layer "F.Fab")
		)
		(fp_line
			(start -0.2794 0.9906)
			(end 0.2794 0.9906)
			(stroke
				(width 0.1)
				(type default)
			)
			(layer "F.Fab")
		)
		(pad "1" smd rect
			(at 0 0 90)
			(size 0.508 0.508)
			(layers "F.Cu" "F.Mask" "F.Paste")
			(net "VR_P5V_STBY_COMP")
		)
		(pad "2" smd rect
			(at 0 0.889 90)
			(size 0.508 0.508)
			(layers "F.Cu" "F.Mask" "F.Paste")
			(net "VR_P5V_STBY_RC_COMP")
		)
		(zone
			(layer "F.Cu")
			(hatch none 0.5)
			(connect_pads
				(clearance 0)
			)
			(min_thickness 0.25)
			(keepout
				(tracks allowed)
				(vias not_allowed)
				(pads allowed)
				(copperpour not_allowed)
				(footprints allowed)
			)
			(placement
				(enabled no)
				(sheetname "")
			)
			(fill
				(thermal_gap 0.5)
				(thermal_bridge_width 0.5)
				(island_removal_mode 0)
			)
			(polygon
				(pts
					(xy 393.039346 -64.705738) (xy 393.039346 -65.213738) (xy 393.420346 -65.213738) (xy 393.420346 -64.705738)
				)
			)
		)
		(zone
			(layer "F.Cu")
			(hatch none 0.5)
			(connect_pads
				(clearance 0)
			)
			(min_thickness 0.25)
			(keepout
				(tracks not_allowed)
				(vias allowed)
				(pads allowed)
				(copperpour not_allowed)
				(footprints allowed)
			)
			(placement
				(enabled no)
				(sheetname "")
			)
			(fill
				(thermal_gap 0.5)
				(thermal_bridge_width 0.5)
				(island_removal_mode 0)
			)
			(polygon
				(pts
					(xy 393.420346 -64.705738) (xy 393.420346 -65.213738) (xy 393.039346 -65.213738) (xy 393.039346 -64.705738)
				)
			)
		)
	)
	(footprint ""
		(layer "F.Cu")
		(at 214.503 -78.4098)
		(property "Reference" "C4D12"
			(at 0 0 0)
			(layer "F.SilkS")
			(hide yes)
			(effects
				(font
					(size 1.27 1.27)
				)
			)
		)
		(property "Value" ""
			(at 0 0 0)
			(layer "F.Fab")
			(effects
				(font
					(size 1.27 1.27)
				)
			)
		)
		(duplicate_pad_numbers_are_jumpers no)
		(fp_poly
			(pts
				(xy -0.4953 -0.2032) (xy 0.4953 -0.2032) (xy 0.4953 1.6002) (xy -0.4953 1.6002)
			)
			(stroke
				(width 0)
				(type default)
			)
			(fill no)
			(layer "F.CrtYd")
		)
		(fp_line
			(start -0.4953 -0.2032)
			(end 0.4953 -0.2032)
			(stroke
				(width 0.1)
				(type default)
			)
			(layer "F.Fab")
		)
		(fp_line
			(start -0.4953 1.6002)
			(end -0.4953 -0.2032)
			(stroke
				(width 0.1)
				(type default)
			)
			(layer "F.Fab")
		)
		(fp_line
			(start 0.4953 -0.2032)
			(end 0.4953 1.6002)
			(stroke
				(width 0.1)
				(type default)
			)
			(layer "F.Fab")
		)
		(fp_line
			(start 0.4953 1.6002)
			(end -0.4953 1.6002)
			(stroke
				(width 0.1)
				(type default)
			)
			(layer "F.Fab")
		)
		(pad "1" smd rect
			(at 0 0)
			(size 0.762 0.889)
			(layers "F.Cu" "F.Mask" "F.Paste")
			(net "PVCCIN_CPU0")
		)
		(pad "2" smd rect
			(at 0 1.397)
			(size 0.762 0.889)
			(layers "F.Cu" "F.Mask" "F.Paste")
			(net "GND")
		)
		(zone
			(layer "F.Cu")
			(hatch none 0.5)
			(connect_pads
				(clearance 0)
			)
			(min_thickness 0.25)
			(keepout
				(tracks not_allowed)
				(vias allowed)
				(pads allowed)
				(copperpour not_allowed)
				(footprints allowed)
			)
			(placement
				(enabled no)
				(sheetname "")
			)
			(fill
				(thermal_gap 0.5)
				(thermal_bridge_width 0.5)
				(island_removal_mode 0)
			)
			(polygon
				(pts
					(xy 214.122 -77.9653) (xy 214.884 -77.9653) (xy 214.884 -77.4573) (xy 214.122 -77.4573)
				)
			)
		)
	)
	(footprint ""
		(layer "F.Cu")
		(at 386.417566 -141.471396 -90)
		(property "Reference" "C7B18"
			(at 0 0 270)
			(layer "F.SilkS")
			(hide yes)
			(effects
				(font
					(size 1.27 1.27)
				)
			)
		)
		(property "Value" ""
			(at 0 0 270)
			(layer "F.Fab")
			(effects
				(font
					(size 1.27 1.27)
				)
			)
		)
		(duplicate_pad_numbers_are_jumpers no)
		(fp_rect
			(start -0.4953 1.6002)
			(end 0.4953 -0.2032)
			(stroke
				(width 0)
				(type default)
			)
			(fill no)
			(layer "F.CrtYd")
		)
		(fp_line
			(start -0.4953 1.6002)
			(end -0.4953 -0.2032)
			(stroke
				(width 0.1)
				(type default)
			)
			(layer "F.Fab")
		)
		(fp_line
			(start 0.4953 1.6002)
			(end -0.4953 1.6002)
			(stroke
				(width 0.1)
				(type default)
			)
			(layer "F.Fab")
		)
		(fp_line
			(start -0.4953 -0.2032)
			(end 0.4953 -0.2032)
			(stroke
				(width 0.1)
				(type default)
			)
			(layer "F.Fab")
		)
		(fp_line
			(start 0.4953 -0.2032)
			(end 0.4953 1.6002)
			(stroke
				(width 0.1)
				(type default)
			)
			(layer "F.Fab")
		)
		(pad "1" smd rect
			(at 0 0 270)
			(size 0.762 0.889)
			(layers "F.Cu" "F.Mask" "F.Paste")
			(net "P1V05_PCH_STBY")
		)
		(pad "2" smd rect
			(at 0 1.397 270)
			(size 0.762 0.889)
			(layers "F.Cu" "F.Mask" "F.Paste")
			(net "GND")
		)
		(zone
			(layer "F.Cu")
			(hatch none 0.5)
			(connect_pads
				(clearance 0)
			)
			(min_thickness 0.25)
			(keepout
				(tracks not_allowed)
				(vias allowed)
				(pads allowed)
				(copperpour not_allowed)
				(footprints allowed)
			)
			(placement
				(enabled no)
				(sheetname "")
			)
			(fill
				(thermal_gap 0.5)
				(thermal_bridge_width 0.5)
				(island_removal_mode 0)
			)
			(polygon
				(pts
					(xy 385.465066 -141.852396) (xy 385.465066 -141.090396) (xy 385.973066 -141.090396) (xy 385.973066 -141.852396)
				)
			)
		)
	)
	(footprint ""
		(layer "F.Cu")
		(at 407.749502 -122.011186 90)
		(property "Reference" "R1W16"
			(at -0.8382 -0.67818 90)
			(unlocked yes)
			(layer "F.SilkS")
			(effects
				(font
					(size 0.4064 0.254)
					(thickness 0.1524)
				)
				(justify left)
			)
		)
		(property "Value" ""
			(at 0 0 90)
			(layer "F.Fab")
			(effects
				(font
					(size 1.27 1.27)
				)
			)
		)
		(duplicate_pad_numbers_are_jumpers no)
		(fp_poly
			(pts
				(xy -0.2794 -0.1016) (xy 0.2794 -0.1016) (xy 0.2794 0.9906) (xy -0.2794 0.9906)
			)
			(stroke
				(width 0)
				(type default)
			)
			(fill no)
			(layer "F.CrtYd")
		)
		(fp_line
			(start 0.2794 -0.1016)
			(end -0.2794 -0.1016)
			(stroke
				(width 0.1)
				(type default)
			)
			(layer "F.Fab")
		)
		(fp_line
			(start -0.2794 -0.1016)
			(end -0.2794 0.9906)
			(stroke
				(width 0.1)
				(type default)
			)
			(layer "F.Fab")
		)
		(fp_line
			(start 0.2794 0.9906)
			(end 0.2794 -0.1016)
			(stroke
				(width 0.1)
				(type default)
			)
			(layer "F.Fab")
		)
		(fp_line
			(start -0.2794 0.9906)
			(end 0.2794 0.9906)
			(stroke
				(width 0.1)
				(type default)
			)
			(layer "F.Fab")
		)
		(pad "1" smd rect
			(at 0 0 90)
			(size 0.508 0.508)
			(layers "F.Cu" "F.Mask" "F.Paste")
			(net "USB_PCH_BMC_P4_DP_R")
		)
		(pad "2" smd rect
			(at 0 0.889 90)
			(size 0.508 0.508)
			(layers "F.Cu" "F.Mask" "F.Paste")
			(net "USB_PCH_BMC_P4_DP")
		)
		(zone
			(layer "F.Cu")
			(hatch none 0.5)
			(connect_pads
				(clearance 0)
			)
			(min_thickness 0.25)
			(keepout
				(tracks allowed)
				(vias not_allowed)
				(pads allowed)
				(copperpour not_allowed)
				(footprints allowed)
			)
			(placement
				(enabled no)
				(sheetname "")
			)
			(fill
				(thermal_gap 0.5)
				(thermal_bridge_width 0.5)
				(island_removal_mode 0)
			)
			(polygon
				(pts
					(xy 408.003502 -121.757186) (xy 408.003502 -122.265186) (xy 408.384502 -122.265186) (xy 408.384502 -121.757186)
				)
			)
		)
		(zone
			(layer "F.Cu")
			(hatch none 0.5)
			(connect_pads
				(clearance 0)
			)
			(min_thickness 0.25)
			(keepout
				(tracks not_allowed)
				(vias allowed)
				(pads allowed)
				(copperpour not_allowed)
				(footprints allowed)
			)
			(placement
				(enabled no)
				(sheetname "")
			)
			(fill
				(thermal_gap 0.5)
				(thermal_bridge_width 0.5)
				(island_removal_mode 0)
			)
			(polygon
				(pts
					(xy 408.384502 -121.757186) (xy 408.384502 -122.265186) (xy 408.003502 -122.265186) (xy 408.003502 -121.757186)
				)
			)
		)
	)
	(footprint ""
		(layer "F.Cu")
		(at 351.51568 -139.37742 -90)
		(property "Reference" "R7A10"
			(at 0 0 270)
			(layer "F.SilkS")
			(hide yes)
			(effects
				(font
					(size 1.27 1.27)
				)
			)
		)
		(property "Value" ""
			(at 0 0 270)
			(layer "F.Fab")
			(effects
				(font
					(size 1.27 1.27)
				)
			)
		)
		(duplicate_pad_numbers_are_jumpers no)
		(fp_poly
			(pts
				(xy -0.2794 -0.1016) (xy 0.2794 -0.1016) (xy 0.2794 0.9906) (xy -0.2794 0.9906)
			)
			(stroke
				(width 0)
				(type default)
			)
			(fill no)
			(layer "F.CrtYd")
		)
		(fp_line
			(start -0.2794 0.9906)
			(end 0.2794 0.9906)
			(stroke
				(width 0.1)
				(type default)
			)
			(layer "F.Fab")
		)
		(fp_line
			(start 0.2794 0.9906)
			(end 0.2794 -0.1016)
			(stroke
				(width 0.1)
				(type default)
			)
			(layer "F.Fab")
		)
		(fp_line
			(start -0.2794 -0.1016)
			(end -0.2794 0.9906)
			(stroke
				(width 0.1)
				(type default)
			)
			(layer "F.Fab")
		)
		(fp_line
			(start 0.2794 -0.1016)
			(end -0.2794 -0.1016)
			(stroke
				(width 0.1)
				(type default)
			)
			(layer "F.Fab")
		)
		(pad "1" smd rect
			(at 0 0 270)
			(size 0.508 0.508)
			(layers "F.Cu" "F.Mask" "F.Paste")
			(net "VR_PVDDQ_DEF_XADDR1")
		)
		(pad "2" smd rect
			(at 0 0.889 270)
			(size 0.508 0.508)
			(layers "F.Cu" "F.Mask" "F.Paste")
			(net "GND")
		)
		(zone
			(layer "F.Cu")
			(hatch none 0.5)
			(connect_pads
				(clearance 0)
			)
			(min_thickness 0.25)
			(keepout
				(tracks not_allowed)
				(vias allowed)
				(pads allowed)
				(copperpour not_allowed)
				(footprints allowed)
			)
			(placement
				(enabled no)
				(sheetname "")
			)
			(fill
				(thermal_gap 0.5)
				(thermal_bridge_width 0.5)
				(island_removal_mode 0)
			)
			(polygon
				(pts
					(xy 350.88068 -139.63142) (xy 350.88068 -139.12342) (xy 351.26168 -139.12342) (xy 351.26168 -139.63142)
				)
			)
		)
		(zone
			(layer "F.Cu")
			(hatch none 0.5)
			(connect_pads
				(clearance 0)
			)
			(min_thickness 0.25)
			(keepout
				(tracks allowed)
				(vias not_allowed)
				(pads allowed)
				(copperpour not_allowed)
				(footprints allowed)
			)
			(placement
				(enabled no)
				(sheetname "")
			)
			(fill
				(thermal_gap 0.5)
				(thermal_bridge_width 0.5)
				(island_removal_mode 0)
			)
			(polygon
				(pts
					(xy 351.26168 -139.63142) (xy 351.26168 -139.12342) (xy 350.88068 -139.12342) (xy 350.88068 -139.63142)
				)
			)
		)
	)
	(footprint ""
		(layer "F.Cu")
		(at 193.675 -13.3985)
		(property "Reference" "R4G2"
			(at 0 0 0)
			(layer "F.SilkS")
			(hide yes)
			(effects
				(font
					(size 1.27 1.27)
				)
			)
		)
		(property "Value" ""
			(at 0 0 0)
			(layer "F.Fab")
			(effects
				(font
					(size 1.27 1.27)
				)
			)
		)
		(duplicate_pad_numbers_are_jumpers no)
		(fp_poly
			(pts
				(xy -0.2794 -0.1016) (xy 0.2794 -0.1016) (xy 0.2794 0.9906) (xy -0.2794 0.9906)
			)
			(stroke
				(width 0)
				(type default)
			)
			(fill no)
			(layer "F.CrtYd")
		)
		(fp_line
			(start -0.2794 -0.1016)
			(end -0.2794 0.9906)
			(stroke
				(width 0.1)
				(type default)
			)
			(layer "F.Fab")
		)
		(fp_line
			(start -0.2794 0.9906)
			(end 0.2794 0.9906)
			(stroke
				(width 0.1)
				(type default)
			)
			(layer "F.Fab")
		)
		(fp_line
			(start 0.2794 -0.1016)
			(end -0.2794 -0.1016)
			(stroke
				(width 0.1)
				(type default)
			)
			(layer "F.Fab")
		)
		(fp_line
			(start 0.2794 0.9906)
			(end 0.2794 -0.1016)
			(stroke
				(width 0.1)
				(type default)
			)
			(layer "F.Fab")
		)
		(pad "1" smd rect
			(at 0 0)
			(size 0.508 0.508)
			(layers "F.Cu" "F.Mask" "F.Paste")
			(net "PVDDQ_ABC")
		)
		(pad "2" smd rect
			(at 0 0.889)
			(size 0.508 0.508)
			(layers "F.Cu" "F.Mask" "F.Paste")
			(net "M_B_VREF")
		)
		(zone
			(layer "F.Cu")
			(hatch none 0.5)
			(connect_pads
				(clearance 0)
			)
			(min_thickness 0.25)
			(keepout
				(tracks allowed)
				(vias not_allowed)
				(pads allowed)
				(copperpour not_allowed)
				(footprints allowed)
			)
			(placement
				(enabled no)
				(sheetname "")
			)
			(fill
				(thermal_gap 0.5)
				(thermal_bridge_width 0.5)
				(island_removal_mode 0)
			)
			(polygon
				(pts
					(xy 193.421 -13.1445) (xy 193.929 -13.1445) (xy 193.929 -12.7635) (xy 193.421 -12.7635)
				)
			)
		)
		(zone
			(layer "F.Cu")
			(hatch none 0.5)
			(connect_pads
				(clearance 0)
			)
			(min_thickness 0.25)
			(keepout
				(tracks not_allowed)
				(vias allowed)
				(pads allowed)
				(copperpour not_allowed)
				(footprints allowed)
			)
			(placement
				(enabled no)
				(sheetname "")
			)
			(fill
				(thermal_gap 0.5)
				(thermal_bridge_width 0.5)
				(island_removal_mode 0)
			)
			(polygon
				(pts
					(xy 193.421 -12.7635) (xy 193.929 -12.7635) (xy 193.929 -13.1445) (xy 193.421 -13.1445)
				)
			)
		)
	)
	(footprint ""
		(layer "F.Cu")
		(at 5.1054 -22.2758 90)
		(property "Reference" "C1G2"
			(at 0 0 90)
			(layer "F.SilkS")
			(hide yes)
			(effects
				(font
					(size 1.27 1.27)
				)
			)
		)
		(property "Value" "*"
			(at -0.0762 -6.2357 90)
			(unlocked yes)
			(layer "F.Fab")
			(hide yes)
			(effects
				(font
					(size 1.27 1.016)
					(thickness 0.1524)
				)
			)
		)
		(property "Device Type" "SC22U16V5MX-4-GP_SMD-BCG5-SC22A"
			(at -0.0762 -8.2677 90)
			(unlocked yes)
			(layer "F.Fab")
			(hide yes)
			(effects
				(font
					(size 1.27 1.016)
					(thickness 0.1524)
				)
			)
		)
		(duplicate_pad_numbers_are_jumpers no)
		(fp_line
			(start 0.635 0)
			(end -0.635 0)
			(stroke
				(width 0.508)
				(type default)
			)
			(layer "F.SilkS")
		)
		(fp_rect
			(start -0.9652 1.778)
			(end 0.9652 -1.778)
			(stroke
				(width 0)
				(type default)
			)
			(fill no)
			(layer "F.CrtYd")
		)
		(fp_poly
			(pts
				(xy -0.9652 -1.778) (xy 0.9652 -1.778) (xy 0.9652 1.778) (xy -0.9652 1.778)
			)
			(stroke
				(width 0)
				(type default)
			)
			(fill no)
			(layer "F.Fab")
		)
		(pad "1" smd rect
			(at 0 -0.9652 90)
			(size 1.397 1.143)
			(layers "F.Cu" "F.Mask" "F.Paste")
			(net "VR_FET_SW_P12V_STBY_PVDDQ_GHJ")
		)
		(pad "2" smd rect
			(at 0 0.9652 90)
			(size 1.397 1.143)
			(layers "F.Cu" "F.Mask" "F.Paste")
			(net "GND")
		)
	)
	(footprint ""
		(layer "F.Cu")
		(at 24.8412 -69.3166 90)
		(property "Reference" "Q1D3"
			(at -1.34747 -0.1016 0)
			(unlocked yes)
			(layer "F.SilkS")
			(effects
				(font
					(size 0.7874 0.5842)
					(thickness 0.1524)
				)
				(justify left)
			)
		)
		(property "Value" ""
			(at 0 0 90)
			(layer "F.Fab")
			(effects
				(font
					(size 1.27 1.27)
				)
			)
		)
		(duplicate_pad_numbers_are_jumpers no)
		(fp_line
			(start 1.778 -0.5715)
			(end 1.778 0.3175)
			(stroke
				(width 0.1524)
				(type default)
			)
			(layer "F.SilkS")
		)
		(fp_line
			(start 0.9525 -0.5715)
			(end 1.778 -0.5715)
			(stroke
				(width 0.1524)
				(type default)
			)
			(layer "F.SilkS")
		)
		(fp_line
			(start 0.381 0.635)
			(end 0.381 1.27)
			(stroke
				(width 0.1524)
				(type default)
			)
			(layer "F.SilkS")
		)
		(fp_line
			(start 1.778 2.4765)
			(end 1.778 1.5875)
			(stroke
				(width 0.1524)
				(type default)
			)
			(layer "F.SilkS")
		)
		(fp_line
			(start 0.9525 2.4765)
			(end 1.778 2.4765)
			(stroke
				(width 0.1524)
				(type default)
			)
			(layer "F.SilkS")
		)
		(fp_circle
			(center -1.039368 -0.232156)
			(end -1.039368 -0.105156)
			(stroke
				(width 0.254)
				(type default)
			)
			(fill no)
			(layer "F.SilkS")
		)
		(fp_poly
			(pts
				(xy 1.778 2.4765) (xy 0.381 2.4765) (xy 0.381 -0.5715) (xy 1.778 -0.5715)
			)
			(stroke
				(width 0)
				(type default)
			)
			(fill no)
			(layer "F.CrtYd")
		)
		(fp_line
			(start 1.778 -0.5715)
			(end 0.381 -0.5715)
			(stroke
				(width 0.1)
				(type default)
			)
			(layer "F.Fab")
		)
		(fp_line
			(start 0.381 -0.5715)
			(end 0.381 2.4765)
			(stroke
				(width 0.1)
				(type default)
			)
			(layer "F.Fab")
		)
		(fp_line
			(start 1.778 2.4765)
			(end 1.778 -0.5715)
			(stroke
				(width 0.1)
				(type default)
			)
			(layer "F.Fab")
		)
		(fp_line
			(start 0.381 2.4765)
			(end 1.778 2.4765)
			(stroke
				(width 0.1)
				(type default)
			)
			(layer "F.Fab")
		)
		(fp_circle
			(center -0.9525 -0.9271)
			(end -0.9525 -0.8001)
			(stroke
				(width 0.254)
				(type default)
			)
			(fill no)
			(layer "F.Fab")
		)
		(pad "1" smd rect
			(at 0 0 90)
			(size 1.143 0.508)
			(layers "F.Cu" "F.Mask" "F.Paste")
			(net "TEMP_SENSOR_B")
		)
		(pad "2" smd rect
			(at 0 1.905 90)
			(size 1.143 0.508)
			(layers "F.Cu" "F.Mask" "F.Paste")
			(net "TEMP_SENSOR_E")
		)
		(pad "3" smd rect
			(at 2.159 0.9525 90)
			(size 1.143 0.508)
			(layers "F.Cu" "F.Mask" "F.Paste")
			(net "TEMP_SENSOR_B")
		)
	)
)
